(kicad_pcb
	(version 20241229)
	(generator "pcbnew")
	(generator_version "9.0")
	(general
		(thickness 1.62)
		(legacy_teardrops no)
	)
	(paper "A4")
	(title_block
		(title "OCuLink to 10GbE adapter")
		(date "2026-02-23")
		(rev "1.1.0")
		(company "Antmicro Ltd")
		(comment 1 "www.antmicro.com")
		(comment 9 "footprints 379-384 of 510")
	)
	(layers
		(0 "F.Cu" signal)
		(4 "In1.Cu" signal)
		(6 "In2.Cu" signal)
		(8 "In3.Cu" signal)
		(10 "In4.Cu" signal)
		(12 "In5.Cu" signal)
		(14 "In6.Cu" signal)
		(2 "B.Cu" signal)
		(9 "F.Adhes" user "F.Adhesive")
		(11 "B.Adhes" user "B.Adhesive")
		(13 "F.Paste" user)
		(15 "B.Paste" user)
		(5 "F.SilkS" user "F.Silkscreen")
		(7 "B.SilkS" user "B.Silkscreen")
		(1 "F.Mask" user)
		(3 "B.Mask" user)
		(17 "Dwgs.User" user "User.Drawings")
		(19 "Cmts.User" user "User.Comments")
		(21 "Eco1.User" user "User.Eco1")
		(23 "Eco2.User" user "User.Eco2")
		(25 "Edge.Cuts" user)
		(27 "Margin" user)
		(31 "F.CrtYd" user "F.Courtyard")
		(29 "B.CrtYd" user "B.Courtyard")
		(35 "F.Fab" user)
		(33 "B.Fab" user)
	)
	(footprint "antmicro-footprints:TP_SMD_0.75mm"
		(layer "B.Cu")
		(at 89.3 106.49 90)
		(property "Reference" "TP12"
			(at 0.87 0.36 180)
			(layer "B.SilkS")
			(effects
				(font
					(size 0.7 0.7)
					(thickness 0.15)
				)
				(justify right top mirror)
			)
		)
		(property "Value" "TP_0.75mm_SMD"
			(at 0 -1.2 90)
			(layer "B.Fab")
			(hide yes)
			(effects
				(font
					(size 0.7 0.7)
					(thickness 0.15)
				)
				(justify right top mirror)
			)
		)
		(property "Description" "SMT test point"
			(at 0 0 90)
			(layer "B.Fab")
			(hide yes)
			(effects
				(font
					(size 1.27 1.27)
					(thickness 0.15)
				)
				(justify mirror)
			)
		)
		(property "MPN" ""
			(at 0 0 90)
			(unlocked yes)
			(layer "B.Fab")
			(hide yes)
			(effects
				(font
					(size 1 1)
					(thickness 0.15)
				)
				(justify mirror)
			)
		)
		(property "Manufacturer" ""
			(at 0 0 90)
			(unlocked yes)
			(layer "B.Fab")
			(hide yes)
			(effects
				(font
					(size 1 1)
					(thickness 0.15)
				)
				(justify mirror)
			)
		)
		(property "Author" "Antmicro"
			(at 0 0 90)
			(unlocked yes)
			(layer "B.Fab")
			(hide yes)
			(effects
				(font
					(size 1 1)
					(thickness 0.15)
				)
				(justify mirror)
			)
		)
		(property "License" "Apache-2.0"
			(at 0 0 90)
			(unlocked yes)
			(layer "B.Fab")
			(hide yes)
			(effects
				(font
					(size 1 1)
					(thickness 0.15)
				)
				(justify mirror)
			)
		)
		(sheetname "/X710-AT2 Misc/")
		(sheetfile "x710-at2-mics.kicad_sch")
		(attr exclude_from_pos_files exclude_from_bom)
		(fp_circle
			(center 0 0)
			(end 0.475 0)
			(stroke
				(width 0.05)
				(type default)
			)
			(fill no)
			(layer "B.CrtYd")
		)
		(pad "1" smd circle
			(at 0 0 90)
			(size 0.75 0.75)
			(layers "B.Cu" "B.Mask")
			(net 136 "/X710-AT2 Misc/PHY_TDI")
			(pinfunction "1")
			(pintype "passive")
		)
	)
	(footprint "antmicro-footprints:C_0402_1005Metric"
		(layer "B.Cu")
		(at 86.225 102 90)
		(descr "Capacitor SMD 0402")
		(tags "capacitor SMD 0402")
		(property "Reference" "C116"
			(at 9.09 -0.447343 90)
			(layer "B.SilkS")
			(effects
				(font
					(size 0.7 0.7)
					(thickness 0.15)
				)
				(justify right top mirror)
			)
		)
		(property "Value" "C_1u_25V_0402"
			(at -1.022927 -2.155214 90)
			(layer "B.Fab")
			(hide yes)
			(effects
				(font
					(size 0.7 0.7)
					(thickness 0.15)
				)
				(justify right top mirror)
			)
		)
		(property "Datasheet" "https://www.murata.com/products/productdetail?partno=GRM155R61E105KE11%23"
			(at 0 0 90)
			(layer "B.Fab")
			(hide yes)
			(effects
				(font
					(size 1.27 1.27)
					(thickness 0.15)
				)
				(justify mirror)
			)
		)
		(property "Description" "SMD Multilayer Ceramic Capacitor, 1 µF, 25 V, 0402 [1005 Metric], ± 10%, X5R, GRM Series"
			(at 0 0 90)
			(layer "B.Fab")
			(hide yes)
			(effects
				(font
					(size 1.27 1.27)
					(thickness 0.15)
				)
				(justify mirror)
			)
		)
		(property "MPN" "GRM155R61E105KE11J"
			(at 0 0 90)
			(unlocked yes)
			(layer "B.Fab")
			(hide yes)
			(effects
				(font
					(size 1 1)
					(thickness 0.15)
				)
				(justify mirror)
			)
		)
		(property "Manufacturer" "Murata"
			(at 0 0 90)
			(unlocked yes)
			(layer "B.Fab")
			(hide yes)
			(effects
				(font
					(size 1 1)
					(thickness 0.15)
				)
				(justify mirror)
			)
		)
		(property "License" "Apache-2.0"
			(at 0 0 90)
			(unlocked yes)
			(layer "B.Fab")
			(hide yes)
			(effects
				(font
					(size 1 1)
					(thickness 0.15)
				)
				(justify mirror)
			)
		)
		(property "Author" "Antmicro"
			(at 0 0 90)
			(unlocked yes)
			(layer "B.Fab")
			(hide yes)
			(effects
				(font
					(size 1 1)
					(thickness 0.15)
				)
				(justify mirror)
			)
		)
		(property "Val" "1u"
			(at 0 0 90)
			(unlocked yes)
			(layer "B.Fab")
			(hide yes)
			(effects
				(font
					(size 1 1)
					(thickness 0.15)
				)
				(justify mirror)
			)
		)
		(property "Voltage" "25V"
			(at 0 0 90)
			(unlocked yes)
			(layer "B.Fab")
			(hide yes)
			(effects
				(font
					(size 1 1)
					(thickness 0.15)
				)
				(justify mirror)
			)
		)
		(property "Dielectric" "X5R"
			(at 0 0 90)
			(unlocked yes)
			(layer "B.Fab")
			(hide yes)
			(effects
				(font
					(size 1 1)
					(thickness 0.15)
				)
				(justify mirror)
			)
		)
		(sheetname "/X710-AT2 power/")
		(sheetfile "x710-at2-power.kicad_sch")
		(attr smd)
		(fp_rect
			(start -0.925 0.47)
			(end 0.925 -0.47)
			(stroke
				(width 0.05)
				(type default)
			)
			(fill no)
			(layer "B.CrtYd")
		)
		(fp_line
			(start 0.504 -0.248)
			(end -0.494 -0.248)
			(stroke
				(width 0.15)
				(type solid)
			)
			(layer "B.Fab")
		)
		(fp_line
			(start -0.494 -0.248)
			(end -0.494 0.25)
			(stroke
				(width 0.15)
				(type solid)
			)
			(layer "B.Fab")
		)
		(fp_line
			(start 0.504 0.25)
			(end 0.504 -0.248)
			(stroke
				(width 0.15)
				(type solid)
			)
			(layer "B.Fab")
		)
		(fp_line
			(start -0.494 0.25)
			(end 0.504 0.25)
			(stroke
				(width 0.15)
				(type solid)
			)
			(layer "B.Fab")
		)
		(pad "1" smd roundrect
			(at -0.48 0 90)
			(size 0.59 0.64)
			(layers "B.Cu" "B.Mask" "B.Paste")
			(roundrect_rratio 0.25)
			(net 28 "GND")
			(pintype "passive")
		)
		(pad "2" smd roundrect
			(at 0.48 0 90)
			(size 0.59 0.64)
			(layers "B.Cu" "B.Mask" "B.Paste")
			(roundrect_rratio 0.25)
			(net 9 "VCCD")
			(pintype "passive")
		)
	)
	(footprint "antmicro-footprints:R_0402_1005Metric"
		(layer "B.Cu")
		(at 109.5 66.6 180)
		(descr "Resistor SMD 0402")
		(tags "resistor SMD 0402")
		(property "Reference" "R164"
			(at -1.44 5.61 0)
			(layer "B.SilkS")
			(effects
				(font
					(size 0.7 0.7)
					(thickness 0.15)
				)
				(justify left bottom mirror)
			)
		)
		(property "Value" "R_10k_0402"
			(at -1.011843 -1.772046 0)
			(layer "B.Fab")
			(hide yes)
			(effects
				(font
					(size 0.7 0.7)
					(thickness 0.15)
				)
				(justify left bottom mirror)
			)
		)
		(property "Datasheet" "https://www.bourns.com/docs/product-datasheets/cr.pdf"
			(at 0 0 0)
			(layer "B.Fab")
			(hide yes)
			(effects
				(font
					(size 1.27 1.27)
					(thickness 0.15)
				)
				(justify mirror)
			)
		)
		(property "Description" "SMD Chip Resistor, 10 kohm, ± 1%, 62.5 mW, 0402 [1005 Metric], Thick Film, General Purpose"
			(at 0 0 0)
			(layer "B.Fab")
			(hide yes)
			(effects
				(font
					(size 1.27 1.27)
					(thickness 0.15)
				)
				(justify mirror)
			)
		)
		(property "MPN" "CR0402-FX-1002GLF"
			(at 0 0 180)
			(unlocked yes)
			(layer "B.Fab")
			(hide yes)
			(effects
				(font
					(size 1 1)
					(thickness 0.15)
				)
				(justify mirror)
			)
		)
		(property "Manufacturer" "Bourns"
			(at 0 0 180)
			(unlocked yes)
			(layer "B.Fab")
			(hide yes)
			(effects
				(font
					(size 1 1)
					(thickness 0.15)
				)
				(justify mirror)
			)
		)
		(property "License" "Apache-2.0"
			(at 0 0 180)
			(unlocked yes)
			(layer "B.Fab")
			(hide yes)
			(effects
				(font
					(size 1 1)
					(thickness 0.15)
				)
				(justify mirror)
			)
		)
		(property "Author" "Antmicro"
			(at 0 0 180)
			(unlocked yes)
			(layer "B.Fab")
			(hide yes)
			(effects
				(font
					(size 1 1)
					(thickness 0.15)
				)
				(justify mirror)
			)
		)
		(property "Val" "10k"
			(at 0 0 180)
			(unlocked yes)
			(layer "B.Fab")
			(hide yes)
			(effects
				(font
					(size 1 1)
					(thickness 0.15)
				)
				(justify mirror)
			)
		)
		(property "Tolerance" "1%"
			(at 0 0 180)
			(unlocked yes)
			(layer "B.Fab")
			(hide yes)
			(effects
				(font
					(size 1 1)
					(thickness 0.15)
				)
				(justify mirror)
			)
		)
		(sheetname "/OCuLink/")
		(sheetfile "oculink.kicad_sch")
		(attr smd exclude_from_pos_files exclude_from_bom dnp)
		(fp_rect
			(start -0.925 0.47)
			(end 0.925 -0.47)
			(stroke
				(width 0.05)
				(type default)
			)
			(fill no)
			(layer "B.CrtYd")
		)
		(fp_rect
			(start -0.5 0.25)
			(end 0.5 -0.25)
			(stroke
				(width 0.15)
				(type solid)
			)
			(fill no)
			(layer "B.Fab")
		)
		(pad "1" smd roundrect
			(at -0.48 0 180)
			(size 0.59 0.64)
			(layers "B.Cu" "B.Mask" "B.Paste")
			(roundrect_rratio 0.25)
			(net 319 "/OCuLink/~{PE_ RST}_R")
			(pintype "passive")
		)
		(pad "2" smd roundrect
			(at 0.48 0 180)
			(size 0.59 0.64)
			(layers "B.Cu" "B.Mask" "B.Paste")
			(roundrect_rratio 0.25)
			(net 7 "+3V3")
			(pintype "passive")
		)
	)
	(footprint "antmicro-footprints:R_0402_1005Metric"
		(layer "B.Cu")
		(at 98.48 145.34 90)
		(descr "Resistor SMD 0402")
		(tags "resistor SMD 0402")
		(property "Reference" "R39"
			(at 0.76 -0.32 90)
			(layer "B.SilkS")
			(effects
				(font
					(size 0.7 0.7)
					(thickness 0.15)
				)
				(justify right top mirror)
			)
		)
		(property "Value" "R_220R_0402"
			(at -1.011843 -1.772046 90)
			(layer "B.Fab")
			(hide yes)
			(effects
				(font
					(size 0.7 0.7)
					(thickness 0.15)
				)
				(justify right top mirror)
			)
		)
		(property "Datasheet" "https://www.bourns.com/docs/product-datasheets/cr.pdf"
			(at 0 0 90)
			(layer "B.Fab")
			(hide yes)
			(effects
				(font
					(size 1.27 1.27)
					(thickness 0.15)
				)
				(justify mirror)
			)
		)
		(property "Description" "SMD Chip Resistor, 220 ohm, ± 1%, 62.5 mW, 0402 [1005 Metric], Thick Film, General Purpose"
			(at 0 0 90)
			(layer "B.Fab")
			(hide yes)
			(effects
				(font
					(size 1.27 1.27)
					(thickness 0.15)
				)
				(justify mirror)
			)
		)
		(property "MPN" "CR0402-FX-2200GLF"
			(at 0 0 90)
			(unlocked yes)
			(layer "B.Fab")
			(hide yes)
			(effects
				(font
					(size 1 1)
					(thickness 0.15)
				)
				(justify mirror)
			)
		)
		(property "Manufacturer" "Bourns"
			(at 0 0 90)
			(unlocked yes)
			(layer "B.Fab")
			(hide yes)
			(effects
				(font
					(size 1 1)
					(thickness 0.15)
				)
				(justify mirror)
			)
		)
		(property "License" "Apache-2.0"
			(at 0 0 90)
			(unlocked yes)
			(layer "B.Fab")
			(hide yes)
			(effects
				(font
					(size 1 1)
					(thickness 0.15)
				)
				(justify mirror)
			)
		)
		(property "Author" "Antmicro"
			(at 0 0 90)
			(unlocked yes)
			(layer "B.Fab")
			(hide yes)
			(effects
				(font
					(size 1 1)
					(thickness 0.15)
				)
				(justify mirror)
			)
		)
		(property "Val" "220R"
			(at 0 0 90)
			(unlocked yes)
			(layer "B.Fab")
			(hide yes)
			(effects
				(font
					(size 1 1)
					(thickness 0.15)
				)
				(justify mirror)
			)
		)
		(property "Tolerance" "1%"
			(at 0 0 90)
			(unlocked yes)
			(layer "B.Fab")
			(hide yes)
			(effects
				(font
					(size 1 1)
					(thickness 0.15)
				)
				(justify mirror)
			)
		)
		(sheetname "/2xRJ45/")
		(sheetfile "2xrj45.kicad_sch")
		(attr smd)
		(fp_rect
			(start -0.925 0.47)
			(end 0.925 -0.47)
			(stroke
				(width 0.05)
				(type default)
			)
			(fill no)
			(layer "B.CrtYd")
		)
		(fp_rect
			(start -0.5 0.25)
			(end 0.5 -0.25)
			(stroke
				(width 0.15)
				(type solid)
			)
			(fill no)
			(layer "B.Fab")
		)
		(pad "1" smd roundrect
			(at -0.48 0 90)
			(size 0.59 0.64)
			(layers "B.Cu" "B.Mask" "B.Paste")
			(roundrect_rratio 0.25)
			(net 61 "Net-(J6-LED_YG_Y-)")
			(pintype "passive")
		)
		(pad "2" smd roundrect
			(at 0.48 0 90)
			(size 0.59 0.64)
			(layers "B.Cu" "B.Mask" "B.Paste")
			(roundrect_rratio 0.25)
			(net 86 "/2xRJ45/~{P1_LINK_LESS_THAN_10G}")
			(pintype "passive")
		)
	)
	(footprint "antmicro-footprints:R_0402_1005Metric"
		(layer "B.Cu")
		(at 74.95 103.2 180)
		(descr "Resistor SMD 0402")
		(tags "resistor SMD 0402")
		(property "Reference" "R117"
			(at 0.85 -0.45 0)
			(layer "B.SilkS")
			(effects
				(font
					(size 0.7 0.7)
					(thickness 0.15)
				)
				(justify left bottom mirror)
			)
		)
		(property "Value" "R_1k_0402"
			(at -1.011843 -1.772046 0)
			(layer "B.Fab")
			(hide yes)
			(effects
				(font
					(size 0.7 0.7)
					(thickness 0.15)
				)
				(justify left bottom mirror)
			)
		)
		(property "Datasheet" "https://www.bourns.com/docs/product-datasheets/cr.pdf"
			(at 0 0 0)
			(layer "B.Fab")
			(hide yes)
			(effects
				(font
					(size 1.27 1.27)
					(thickness 0.15)
				)
				(justify mirror)
			)
		)
		(property "Description" "SMD Chip Resistor, 1 kohm, ± 1%, 63 mW, 0402 [1005 Metric], Thick Film, General Purpose"
			(at 0 0 0)
			(layer "B.Fab")
			(hide yes)
			(effects
				(font
					(size 1.27 1.27)
					(thickness 0.15)
				)
				(justify mirror)
			)
		)
		(property "MPN" "CR0402-FX-1001GLF"
			(at 0 0 180)
			(unlocked yes)
			(layer "B.Fab")
			(hide yes)
			(effects
				(font
					(size 1 1)
					(thickness 0.15)
				)
				(justify mirror)
			)
		)
		(property "Manufacturer" "Bourns"
			(at 0 0 180)
			(unlocked yes)
			(layer "B.Fab")
			(hide yes)
			(effects
				(font
					(size 1 1)
					(thickness 0.15)
				)
				(justify mirror)
			)
		)
		(property "License" "Apache-2.0"
			(at 0 0 180)
			(unlocked yes)
			(layer "B.Fab")
			(hide yes)
			(effects
				(font
					(size 1 1)
					(thickness 0.15)
				)
				(justify mirror)
			)
		)
		(property "Author" "Antmicro"
			(at 0 0 180)
			(unlocked yes)
			(layer "B.Fab")
			(hide yes)
			(effects
				(font
					(size 1 1)
					(thickness 0.15)
				)
				(justify mirror)
			)
		)
		(property "Val" "1k"
			(at 0 0 180)
			(unlocked yes)
			(layer "B.Fab")
			(hide yes)
			(effects
				(font
					(size 1 1)
					(thickness 0.15)
				)
				(justify mirror)
			)
		)
		(property "Tolerance" "1%"
			(at 0 0 180)
			(unlocked yes)
			(layer "B.Fab")
			(hide yes)
			(effects
				(font
					(size 1 1)
					(thickness 0.15)
				)
				(justify mirror)
			)
		)
		(sheetname "/X710-AT2 Misc/")
		(sheetfile "x710-at2-mics.kicad_sch")
		(attr smd)
		(fp_rect
			(start -0.925 0.47)
			(end 0.925 -0.47)
			(stroke
				(width 0.05)
				(type default)
			)
			(fill no)
			(layer "B.CrtYd")
		)
		(fp_rect
			(start -0.5 0.25)
			(end 0.5 -0.25)
			(stroke
				(width 0.15)
				(type solid)
			)
			(fill no)
			(layer "B.Fab")
		)
		(pad "1" smd roundrect
			(at -0.48 0 180)
			(size 0.59 0.64)
			(layers "B.Cu" "B.Mask" "B.Paste")
			(roundrect_rratio 0.25)
			(net 113 "/X710-AT2 Misc/RSVDK40_1P88V")
			(pintype "passive")
		)
		(pad "2" smd roundrect
			(at 0.48 0 180)
			(size 0.59 0.64)
			(layers "B.Cu" "B.Mask" "B.Paste")
			(roundrect_rratio 0.25)
			(net 18 "+1V88")
			(pintype "passive")
		)
	)
	(footprint "antmicro-footprints:C_0402_1005Metric"
		(layer "B.Cu")
		(at 79.22 103.23 90)
		(descr "Capacitor SMD 0402")
		(tags "capacitor SMD 0402")
		(property "Reference" "C187"
			(at -11.62 -0.04 90)
			(layer "B.SilkS")
			(effects
				(font
					(size 0.7 0.7)
					(thickness 0.15)
				)
				(justify right top mirror)
			)
		)
		(property "Value" "C_1u_25V_0402"
			(at -1.022927 -2.155213 90)
			(layer "B.Fab")
			(hide yes)
			(effects
				(font
					(size 0.7 0.7)
					(thickness 0.15)
				)
				(justify right top mirror)
			)
		)
		(property "Datasheet" "https://www.murata.com/products/productdetail?partno=GRM155R61E105KE11%23"
			(at 0 0 90)
			(layer "B.Fab")
			(hide yes)
			(effects
				(font
					(size 1.27 1.27)
					(thickness 0.15)
				)
				(justify mirror)
			)
		)
		(property "Description" "SMD Multilayer Ceramic Capacitor, 1 µF, 25 V, 0402 [1005 Metric], ± 10%, X5R, GRM Series"
			(at 0 0 90)
			(layer "B.Fab")
			(hide yes)
			(effects
				(font
					(size 1.27 1.27)
					(thickness 0.15)
				)
				(justify mirror)
			)
		)
		(property "MPN" "GRM155R61E105KE11J"
			(at 0 0 90)
			(unlocked yes)
			(layer "B.Fab")
			(hide yes)
			(effects
				(font
					(size 1 1)
					(thickness 0.15)
				)
				(justify mirror)
			)
		)
		(property "Manufacturer" "Murata"
			(at 0 0 90)
			(unlocked yes)
			(layer "B.Fab")
			(hide yes)
			(effects
				(font
					(size 1 1)
					(thickness 0.15)
				)
				(justify mirror)
			)
		)
		(property "License" "Apache-2.0"
			(at 0 0 90)
			(unlocked yes)
			(layer "B.Fab")
			(hide yes)
			(effects
				(font
					(size 1 1)
					(thickness 0.15)
				)
				(justify mirror)
			)
		)
		(property "Author" "Antmicro"
			(at 0 0 90)
			(unlocked yes)
			(layer "B.Fab")
			(hide yes)
			(effects
				(font
					(size 1 1)
					(thickness 0.15)
				)
				(justify mirror)
			)
		)
		(property "Val" "1u"
			(at 0 0 90)
			(unlocked yes)
			(layer "B.Fab")
			(hide yes)
			(effects
				(font
					(size 1 1)
					(thickness 0.15)
				)
				(justify mirror)
			)
		)
		(property "Voltage" "25V"
			(at 0 0 90)
			(unlocked yes)
			(layer "B.Fab")
			(hide yes)
			(effects
				(font
					(size 1 1)
					(thickness 0.15)
				)
				(justify mirror)
			)
		)
		(property "Dielectric" "X5R"
			(at 0 0 90)
			(unlocked yes)
			(layer "B.Fab")
			(hide yes)
			(effects
				(font
					(size 1 1)
					(thickness 0.15)
				)
				(justify mirror)
			)
		)
		(sheetname "/X710-AT2 power/")
		(sheetfile "x710-at2-power.kicad_sch")
		(attr smd)
		(fp_rect
			(start -0.925 0.47)
			(end 0.925 -0.47)
			(stroke
				(width 0.05)
				(type default)
			)
			(fill no)
			(layer "B.CrtYd")
		)
		(fp_line
			(start 0.504 -0.248)
			(end -0.494 -0.248)
			(stroke
				(width 0.15)
				(type solid)
			)
			(layer "B.Fab")
		)
		(fp_line
			(start -0.494 -0.248)
			(end -0.494 0.25)
			(stroke
				(width 0.15)
				(type solid)
			)
			(layer "B.Fab")
		)
		(fp_line
			(start 0.504 0.25)
			(end 0.504 -0.248)
			(stroke
				(width 0.15)
				(type solid)
			)
			(layer "B.Fab")
		)
		(fp_line
			(start -0.494 0.25)
			(end 0.504 0.25)
			(stroke
				(width 0.15)
				(type solid)
			)
			(layer "B.Fab")
		)
		(pad "1" smd roundrect
			(at -0.48 0 90)
			(size 0.59 0.64)
			(layers "B.Cu" "B.Mask" "B.Paste")
			(roundrect_rratio 0.25)
			(net 28 "GND")
			(pintype "passive")
		)
		(pad "2" smd roundrect
			(at 0.48 0 90)
			(size 0.59 0.64)
			(layers "B.Cu" "B.Mask" "B.Paste")
			(roundrect_rratio 0.25)
			(net 24 "XFI_PVDD")
			(pintype "passive")
		)
	)
)
